# BASEBOARD_FAB2 (Tioga Pass) — schematic netlist excerpt (pin names and nets, part order shuffled) for the footprints in the layout excerpt that follows; sources: Cadence DE-HDL packaged netlist, KiCad conversion of Wiwynn_Tioga_Pass_MB.brd

C9N1  CAP  0.22UF 16V 10% X7R  pkg 0402  page 182 : A = P3E_CPU1_PE3_MP_C_TXP<10> ; B = P3E_CPU1_PE3_MP_TXP<10>
R8D22  RES  33.2 1% CHIP  pkg 0402  page 157 : A = RST_BMC_SRST_R2_N ; B = FM_TPM_PRES_RST_N
R9M13  RES  20.0 1% CHIP  pkg 0402  page 163 : A = SMB_PEHPCPU1_STBY_LVC3_R_SDA ; B = SMB_PEHPCPU1_STBY_LVC3_SDA

(kicad_pcb
	(version 20260206)
	(generator "pcbnew")
	(generator_version "10.0")
	(general
		(thickness 1.6)
		(legacy_teardrops no)
	)
	(paper "A4")
	(title_block
		(title "Wiwynn_Tioga_Pass_MB.brd")
		(comment 1 "Tioga Pass / footprints 4270-4272 of 4770")
	)
	(layers
		(0 "F.Cu" signal "TOP")
		(4 "In1.Cu" signal "L2GND")
		(6 "In2.Cu" signal "L3")
		(8 "In3.Cu" signal "L4GND")
		(10 "In4.Cu" signal "L5")
		(12 "In5.Cu" signal "L6GND")
		(14 "In6.Cu" signal "L7VCC")
		(16 "In7.Cu" signal "L8VCC")
		(18 "In8.Cu" signal "L9GND")
		(20 "In9.Cu" signal "L10")
		(22 "In10.Cu" signal "L11GND")
		(24 "In11.Cu" signal "L12")
		(26 "In12.Cu" signal "L13GND")
		(2 "B.Cu" signal "BOTTOM")
		(9 "F.Adhes" user "F.Adhesive")
		(11 "B.Adhes" user "B.Adhesive")
		(13 "F.Paste" user "Package Geometry/Pastemask Top")
		(15 "B.Paste" user "Package Geometry/Pastemask Bottom")
		(5 "F.SilkS" user "Ref Des/Silkscreen Top")
		(7 "B.SilkS" user "Ref Des/Silkscreen Bottom")
		(1 "F.Mask" user "Board Geometry/Soldermask Top")
		(3 "B.Mask" user "Board Geometry/Soldermask Bottom")
		(17 "Dwgs.User" user "User.Drawings")
		(19 "Cmts.User" user "User.Comments")
		(21 "Eco1.User" user "User.Eco1")
		(23 "Eco2.User" user "User.Eco2")
		(25 "Edge.Cuts" user "Board Geometry/Outline")
		(27 "Margin" user)
		(31 "F.CrtYd" user "Package Geometry/Place Bound Top")
		(29 "B.CrtYd" user "Package Geometry/Place Bound Bottom")
		(35 "F.Fab" user "Ref Des/Assembly Top")
		(33 "B.Fab" user "Ref Des/Assembly Bottom")
	)
	(footprint ""
		(layer "B.Cu")
		(at -2.33426 -121.47296 180)
		(property "Reference" "R9M13"
			(at 0 0 0)
			(layer "B.SilkS")
			(hide yes)
			(effects
				(font
					(size 1.27 1.27)
				)
				(justify mirror)
			)
		)
		(property "Value" ""
			(at 0 0 0)
			(layer "B.Fab")
			(effects
				(font
					(size 1.27 1.27)
				)
				(justify mirror)
			)
		)
		(duplicate_pad_numbers_are_jumpers no)
		(fp_rect
			(start 0.2794 -0.1016)
			(end -0.2794 0.9906)
			(stroke
				(width 0)
				(type default)
			)
			(fill no)
			(layer "B.CrtYd")
		)
		(fp_line
			(start 0.2794 0.9906)
			(end -0.2794 0.9906)
			(stroke
				(width 0.1)
				(type default)
			)
			(layer "B.Fab")
		)
		(fp_line
			(start 0.2794 -0.1016)
			(end 0.2794 0.9906)
			(stroke
				(width 0.1)
				(type default)
			)
			(layer "B.Fab")
		)
		(fp_line
			(start -0.2794 0.9906)
			(end -0.2794 -0.1016)
			(stroke
				(width 0.1)
				(type default)
			)
			(layer "B.Fab")
		)
		(fp_line
			(start -0.2794 -0.1016)
			(end 0.2794 -0.1016)
			(stroke
				(width 0.1)
				(type default)
			)
			(layer "B.Fab")
		)
		(pad "1" smd rect
			(at 0 0)
			(size 0.508 0.508)
			(layers "B.Cu" "B.Mask" "B.Paste")
			(net "SMB_PEHPCPU1_STBY_LVC3_R_SDA")
		)
		(pad "2" smd rect
			(at 0 0.889)
			(size 0.508 0.508)
			(layers "B.Cu" "B.Mask" "B.Paste")
			(net "SMB_PEHPCPU1_STBY_LVC3_SDA")
		)
		(zone
			(layer "B.Cu")
			(hatch none 0.5)
			(connect_pads
				(clearance 0)
			)
			(min_thickness 0.25)
			(keepout
				(tracks not_allowed)
				(vias allowed)
				(pads allowed)
				(copperpour not_allowed)
				(footprints allowed)
			)
			(placement
				(enabled no)
				(sheetname "")
			)
			(fill
				(thermal_gap 0.5)
				(thermal_bridge_width 0.5)
				(island_removal_mode 0)
			)
			(polygon
				(pts
					(xy -2.58826 -121.72696) (xy -2.08026 -121.72696) (xy -2.08026 -122.10796) (xy -2.58826 -122.10796)
				)
			)
		)
		(zone
			(layer "B.Cu")
			(hatch none 0.5)
			(connect_pads
				(clearance 0)
			)
			(min_thickness 0.25)
			(keepout
				(tracks allowed)
				(vias not_allowed)
				(pads allowed)
				(copperpour not_allowed)
				(footprints allowed)
			)
			(placement
				(enabled no)
				(sheetname "")
			)
			(fill
				(thermal_gap 0.5)
				(thermal_bridge_width 0.5)
				(island_removal_mode 0)
			)
			(polygon
				(pts
					(xy -2.58826 -121.72696) (xy -2.08026 -121.72696) (xy -2.08026 -122.10796) (xy -2.58826 -122.10796)
				)
			)
		)
	)
	(footprint ""
		(layer "B.Cu")
		(at 16.82242 -108.83392 90)
		(property "Reference" "C9N1"
			(at 0 0 90)
			(layer "B.SilkS")
			(hide yes)
			(effects
				(font
					(size 1.27 1.27)
				)
				(justify mirror)
			)
		)
		(property "Value" ""
			(at 0 0 90)
			(layer "B.Fab")
			(effects
				(font
					(size 1.27 1.27)
				)
				(justify mirror)
			)
		)
		(duplicate_pad_numbers_are_jumpers no)
		(fp_poly
			(pts
				(xy -0.3048 -0.1016) (xy -0.3048 0.9906) (xy 0.3048 0.9906) (xy 0.3048 -0.1016)
			)
			(stroke
				(width 0)
				(type default)
			)
			(fill no)
			(layer "B.CrtYd")
		)
		(fp_line
			(start 0.3048 -0.1016)
			(end 0.3048 0.9906)
			(stroke
				(width 0.1)
				(type default)
			)
			(layer "B.Fab")
		)
		(fp_line
			(start -0.3048 -0.1016)
			(end 0.3048 -0.1016)
			(stroke
				(width 0.1)
				(type default)
			)
			(layer "B.Fab")
		)
		(fp_line
			(start 0.3048 0.9906)
			(end -0.3048 0.9906)
			(stroke
				(width 0.1)
				(type default)
			)
			(layer "B.Fab")
		)
		(fp_line
			(start -0.3048 0.9906)
			(end -0.3048 -0.1016)
			(stroke
				(width 0.1)
				(type default)
			)
			(layer "B.Fab")
		)
		(pad "1" smd rect
			(at 0 0 270)
			(size 0.508 0.508)
			(layers "B.Cu" "B.Mask" "B.Paste")
			(net "P3E_CPU1_PE3_MP_C_TXP<10>")
		)
		(pad "2" smd rect
			(at 0 0.889 270)
			(size 0.508 0.508)
			(layers "B.Cu" "B.Mask" "B.Paste")
			(net "P3E_CPU1_PE3_MP_TXP<10>")
		)
		(zone
			(layer "B.Cu")
			(hatch none 0.5)
			(connect_pads
				(clearance 0)
			)
			(min_thickness 0.25)
			(keepout
				(tracks allowed)
				(vias not_allowed)
				(pads allowed)
				(copperpour not_allowed)
				(footprints allowed)
			)
			(placement
				(enabled no)
				(sheetname "")
			)
			(fill
				(thermal_gap 0.5)
				(thermal_bridge_width 0.5)
				(island_removal_mode 0)
			)
			(polygon
				(pts
					(xy 17.07642 -109.08792) (xy 17.07642 -108.57992) (xy 17.45742 -108.57992) (xy 17.45742 -109.08792)
				)
			)
		)
		(zone
			(layer "B.Cu")
			(hatch none 0.5)
			(connect_pads
				(clearance 0)
			)
			(min_thickness 0.25)
			(keepout
				(tracks not_allowed)
				(vias allowed)
				(pads allowed)
				(copperpour not_allowed)
				(footprints allowed)
			)
			(placement
				(enabled no)
				(sheetname "")
			)
			(fill
				(thermal_gap 0.5)
				(thermal_bridge_width 0.5)
				(island_removal_mode 0)
			)
			(polygon
				(pts
					(xy 17.45742 -109.08792) (xy 17.45742 -108.57992) (xy 17.07642 -108.57992) (xy 17.07642 -109.08792)
				)
			)
		)
	)
	(footprint ""
		(layer "B.Cu")
		(at 456.025758 -31.173674 180)
		(property "Reference" "R8D22"
			(at 0 0 0)
			(layer "B.SilkS")
			(hide yes)
			(effects
				(font
					(size 1.27 1.27)
				)
				(justify mirror)
			)
		)
		(property "Value" ""
			(at 0 0 0)
			(layer "B.Fab")
			(effects
				(font
					(size 1.27 1.27)
				)
				(justify mirror)
			)
		)
		(duplicate_pad_numbers_are_jumpers no)
		(fp_poly
			(pts
				(xy 0.2794 -0.1016) (xy -0.2794 -0.1016) (xy -0.2794 0.9906) (xy 0.2794 0.9906)
			)
			(stroke
				(width 0)
				(type default)
			)
			(fill no)
			(layer "B.CrtYd")
		)
		(fp_line
			(start 0.2794 0.9906)
			(end -0.2794 0.9906)
			(stroke
				(width 0.1)
				(type default)
			)
			(layer "B.Fab")
		)
		(fp_line
			(start 0.2794 -0.1016)
			(end 0.2794 0.9906)
			(stroke
				(width 0.1)
				(type default)
			)
			(layer "B.Fab")
		)
		(fp_line
			(start -0.2794 0.9906)
			(end -0.2794 -0.1016)
			(stroke
				(width 0.1)
				(type default)
			)
			(layer "B.Fab")
		)
		(fp_line
			(start -0.2794 -0.1016)
			(end 0.2794 -0.1016)
			(stroke
				(width 0.1)
				(type default)
			)
			(layer "B.Fab")
		)
		(pad "1" smd rect
			(at 0 0)
			(size 0.508 0.508)
			(layers "B.Cu" "B.Mask" "B.Paste")
			(net "RST_BMC_SRST_R2_N")
		)
		(pad "2" smd rect
			(at 0 0.889)
			(size 0.508 0.508)
			(layers "B.Cu" "B.Mask" "B.Paste")
			(net "FM_TPM_PRES_RST_N")
		)
		(zone
			(layer "B.Cu")
			(hatch none 0.5)
			(connect_pads
				(clearance 0)
			)
			(min_thickness 0.25)
			(keepout
				(tracks not_allowed)
				(vias allowed)
				(pads allowed)
				(copperpour not_allowed)
				(footprints allowed)
			)
			(placement
				(enabled no)
				(sheetname "")
			)
			(fill
				(thermal_gap 0.5)
				(thermal_bridge_width 0.5)
				(island_removal_mode 0)
			)
			(polygon
				(pts
					(xy 455.771758 -31.808674) (xy 456.279758 -31.808674) (xy 456.279758 -31.427674) (xy 455.771758 -31.427674)
				)
			)
		)
		(zone
			(layer "B.Cu")
			(hatch none 0.5)
			(connect_pads
				(clearance 0)
			)
			(min_thickness 0.25)
			(keepout
				(tracks allowed)
				(vias not_allowed)
				(pads allowed)
				(copperpour not_allowed)
				(footprints allowed)
			)
			(placement
				(enabled no)
				(sheetname "")
			)
			(fill
				(thermal_gap 0.5)
				(thermal_bridge_width 0.5)
				(island_removal_mode 0)
			)
			(polygon
				(pts
					(xy 455.771758 -31.427674) (xy 456.279758 -31.427674) (xy 456.279758 -31.808674) (xy 455.771758 -31.808674)
				)
			)
		)
	)
)
